(kicad_pcb
	(version 20260206)
	(generator "pcbnew")
	(generator_version "10.0")
	(general
		(thickness 1.6)
		(legacy_teardrops no)
	)
	(paper "A4")
	(title_block
		(title "12092022_DA0F0TMDCD0_F0T_Management_Board_D_brd_V3_OCP.brd")
		(comment 1 "Grand Teton / footprints 862-867 of 1440")
	)
	(layers
		(0 "F.Cu" signal "TOP")
		(4 "In1.Cu" signal "GND")
		(6 "In2.Cu" signal "IN1")
		(8 "In3.Cu" signal "GND1")
		(10 "In4.Cu" signal "IN2")
		(12 "In5.Cu" signal "VCC")
		(14 "In6.Cu" signal "VCC1")
		(16 "In7.Cu" signal "IN3")
		(18 "In8.Cu" signal "GND2")
		(20 "In9.Cu" signal "IN4")
		(22 "In10.Cu" signal "GND3")
		(2 "B.Cu" signal "BOTTOM")
		(9 "F.Adhes" user "F.Adhesive")
		(11 "B.Adhes" user "B.Adhesive")
		(13 "F.Paste" user "Package Geometry/Pastemask Top")
		(15 "B.Paste" user "Package Geometry/Pastemask Bottom")
		(5 "F.SilkS" user "Ref Des/Silkscreen Top")
		(7 "B.SilkS" user "Ref Des/Silkscreen Bottom")
		(1 "F.Mask" user "Board Geometry/Soldermask Top")
		(3 "B.Mask" user "Board Geometry/Soldermask Bottom")
		(17 "Dwgs.User" user "User.Drawings")
		(19 "Cmts.User" user "User.Comments")
		(21 "Eco1.User" user "User.Eco1")
		(23 "Eco2.User" user "User.Eco2")
		(25 "Edge.Cuts" user "Board Geometry/Outline")
		(27 "Margin" user)
		(31 "F.CrtYd" user "Package Geometry/Place Bound Top")
		(29 "B.CrtYd" user "Package Geometry/Place Bound Bottom")
		(35 "F.Fab" user "Ref Des/Assembly Top")
		(33 "B.Fab" user "Ref Des/Assembly Bottom")
	)
	(footprint ""
		(layer "B.Cu")
		(at 41.91 -43.053 180)
		(property "Reference" "R168"
			(at 0 0 0)
			(layer "B.SilkS")
			(hide yes)
			(effects
				(font
					(size 1.27 1.27)
				)
				(justify mirror)
			)
		)
		(property "Value" ""
			(at 0 0 0)
			(layer "B.Fab")
			(effects
				(font
					(size 1.27 1.27)
				)
				(justify mirror)
			)
		)
		(duplicate_pad_numbers_are_jumpers no)
		(fp_line
			(start 0.7874 0.4064)
			(end 0.7874 -0.4064)
			(stroke
				(width 0.1524)
				(type default)
			)
			(layer "B.SilkS")
		)
		(fp_line
			(start 0.7874 -0.4064)
			(end -0.7874 -0.4064)
			(stroke
				(width 0.1524)
				(type default)
			)
			(layer "B.SilkS")
		)
		(fp_line
			(start -0.7874 0.4064)
			(end 0.7874 0.4064)
			(stroke
				(width 0.1524)
				(type default)
			)
			(layer "B.SilkS")
		)
		(fp_line
			(start -0.7874 -0.4064)
			(end -0.7874 0.4064)
			(stroke
				(width 0.1524)
				(type default)
			)
			(layer "B.SilkS")
		)
		(fp_line
			(start 0.67945 0.3048)
			(end 0.67945 -0.305054)
			(stroke
				(width 0.1)
				(type default)
			)
			(layer "B.Fab")
		)
		(fp_line
			(start 0.67945 -0.305054)
			(end 0.12065 -0.305054)
			(stroke
				(width 0.1)
				(type default)
			)
			(layer "B.Fab")
		)
		(fp_line
			(start 0.12065 0.3048)
			(end 0.67945 0.3048)
			(stroke
				(width 0.1)
				(type default)
			)
			(layer "B.Fab")
		)
		(fp_line
			(start 0.12065 0.2794)
			(end 0.12065 0.3048)
			(stroke
				(width 0.1)
				(type default)
			)
			(layer "B.Fab")
		)
		(fp_line
			(start 0.12065 -0.2794)
			(end -0.12065 -0.2794)
			(stroke
				(width 0.1)
				(type default)
			)
			(layer "B.Fab")
		)
		(fp_line
			(start 0.12065 -0.305054)
			(end 0.12065 -0.2794)
			(stroke
				(width 0.1)
				(type default)
			)
			(layer "B.Fab")
		)
		(fp_line
			(start -0.120396 0.3048)
			(end -0.120396 0.2794)
			(stroke
				(width 0.1)
				(type default)
			)
			(layer "B.Fab")
		)
		(fp_line
			(start -0.120396 0.2794)
			(end 0.12065 0.2794)
			(stroke
				(width 0.1)
				(type default)
			)
			(layer "B.Fab")
		)
		(fp_line
			(start -0.12065 -0.2794)
			(end -0.12065 -0.3048)
			(stroke
				(width 0.1)
				(type default)
			)
			(layer "B.Fab")
		)
		(fp_line
			(start -0.12065 -0.3048)
			(end -0.67945 -0.3048)
			(stroke
				(width 0.1)
				(type default)
			)
			(layer "B.Fab")
		)
		(fp_line
			(start -0.67945 0.3048)
			(end -0.120396 0.3048)
			(stroke
				(width 0.1)
				(type default)
			)
			(layer "B.Fab")
		)
		(fp_line
			(start -0.67945 -0.3048)
			(end -0.67945 0.3048)
			(stroke
				(width 0.1)
				(type default)
			)
			(layer "B.Fab")
		)
		(pad "1" smd circle
			(at 0.40005 0)
			(size 0 0)
			(layers "B.Cu" "B.Mask" "B.Paste")
			(net "RST_PLTRST_N")
		)
		(pad "2" smd circle
			(at -0.40005 0)
			(size 0 0)
			(layers "B.Cu" "B.Mask" "B.Paste")
			(net "RST_PLTRST_R_N")
		)
	)
	(footprint ""
		(layer "B.Cu")
		(at 52.891182 -70.799706)
		(property "Reference" "C277"
			(at 0 0 0)
			(layer "B.SilkS")
			(hide yes)
			(effects
				(font
					(size 1.27 1.27)
				)
				(justify mirror)
			)
		)
		(property "Value" ""
			(at 0 0 0)
			(layer "B.Fab")
			(effects
				(font
					(size 1.27 1.27)
				)
				(justify mirror)
			)
		)
		(duplicate_pad_numbers_are_jumpers no)
		(fp_line
			(start -0.7874 -0.4064)
			(end -0.7874 0.4064)
			(stroke
				(width 0.1524)
				(type default)
			)
			(layer "B.SilkS")
		)
		(fp_line
			(start -0.7874 0.4064)
			(end 0.7874 0.4064)
			(stroke
				(width 0.1524)
				(type default)
			)
			(layer "B.SilkS")
		)
		(fp_line
			(start 0.7874 -0.4064)
			(end -0.7874 -0.4064)
			(stroke
				(width 0.1524)
				(type default)
			)
			(layer "B.SilkS")
		)
		(fp_line
			(start 0.7874 0.4064)
			(end 0.7874 -0.4064)
			(stroke
				(width 0.1524)
				(type default)
			)
			(layer "B.SilkS")
		)
		(fp_line
			(start -0.67945 -0.3048)
			(end -0.67945 0.3048)
			(stroke
				(width 0.1)
				(type default)
			)
			(layer "B.Fab")
		)
		(fp_line
			(start -0.67945 0.3048)
			(end -0.120396 0.3048)
			(stroke
				(width 0.1)
				(type default)
			)
			(layer "B.Fab")
		)
		(fp_line
			(start -0.12065 -0.3048)
			(end -0.67945 -0.3048)
			(stroke
				(width 0.1)
				(type default)
			)
			(layer "B.Fab")
		)
		(fp_line
			(start -0.12065 -0.2794)
			(end -0.12065 -0.3048)
			(stroke
				(width 0.1)
				(type default)
			)
			(layer "B.Fab")
		)
		(fp_line
			(start -0.120396 0.2794)
			(end 0.12065 0.2794)
			(stroke
				(width 0.1)
				(type default)
			)
			(layer "B.Fab")
		)
		(fp_line
			(start -0.120396 0.3048)
			(end -0.120396 0.2794)
			(stroke
				(width 0.1)
				(type default)
			)
			(layer "B.Fab")
		)
		(fp_line
			(start 0.12065 -0.305054)
			(end 0.12065 -0.2794)
			(stroke
				(width 0.1)
				(type default)
			)
			(layer "B.Fab")
		)
		(fp_line
			(start 0.12065 -0.2794)
			(end -0.12065 -0.2794)
			(stroke
				(width 0.1)
				(type default)
			)
			(layer "B.Fab")
		)
		(fp_line
			(start 0.12065 0.2794)
			(end 0.12065 0.3048)
			(stroke
				(width 0.1)
				(type default)
			)
			(layer "B.Fab")
		)
		(fp_line
			(start 0.12065 0.3048)
			(end 0.67945 0.3048)
			(stroke
				(width 0.1)
				(type default)
			)
			(layer "B.Fab")
		)
		(fp_line
			(start 0.67945 -0.305054)
			(end 0.12065 -0.305054)
			(stroke
				(width 0.1)
				(type default)
			)
			(layer "B.Fab")
		)
		(fp_line
			(start 0.67945 0.3048)
			(end 0.67945 -0.305054)
			(stroke
				(width 0.1)
				(type default)
			)
			(layer "B.Fab")
		)
		(pad "1" smd circle
			(at 0.40005 0 180)
			(size 0 0)
			(layers "B.Cu" "B.Mask" "B.Paste")
			(net "ADCVREFEXT1")
		)
		(pad "2" smd circle
			(at -0.40005 0 180)
			(size 0 0)
			(layers "B.Cu" "B.Mask" "B.Paste")
			(net "GND")
		)
	)
	(footprint ""
		(layer "B.Cu")
		(at 66.802 -13.462 180)
		(property "Reference" "R884"
			(at 0 0 0)
			(layer "B.SilkS")
			(hide yes)
			(effects
				(font
					(size 1.27 1.27)
				)
				(justify mirror)
			)
		)
		(property "Value" ""
			(at 0 0 0)
			(layer "B.Fab")
			(effects
				(font
					(size 1.27 1.27)
				)
				(justify mirror)
			)
		)
		(duplicate_pad_numbers_are_jumpers no)
		(fp_line
			(start 0.7874 0.4064)
			(end 0.7874 -0.4064)
			(stroke
				(width 0.1524)
				(type default)
			)
			(layer "B.SilkS")
		)
		(fp_line
			(start 0.7874 -0.4064)
			(end -0.7874 -0.4064)
			(stroke
				(width 0.1524)
				(type default)
			)
			(layer "B.SilkS")
		)
		(fp_line
			(start -0.7874 0.4064)
			(end 0.7874 0.4064)
			(stroke
				(width 0.1524)
				(type default)
			)
			(layer "B.SilkS")
		)
		(fp_line
			(start -0.7874 -0.4064)
			(end -0.7874 0.4064)
			(stroke
				(width 0.1524)
				(type default)
			)
			(layer "B.SilkS")
		)
		(fp_line
			(start 0.67945 0.3048)
			(end 0.67945 -0.305054)
			(stroke
				(width 0.1)
				(type default)
			)
			(layer "B.Fab")
		)
		(fp_line
			(start 0.67945 -0.305054)
			(end 0.12065 -0.305054)
			(stroke
				(width 0.1)
				(type default)
			)
			(layer "B.Fab")
		)
		(fp_line
			(start 0.12065 0.3048)
			(end 0.67945 0.3048)
			(stroke
				(width 0.1)
				(type default)
			)
			(layer "B.Fab")
		)
		(fp_line
			(start 0.12065 0.2794)
			(end 0.12065 0.3048)
			(stroke
				(width 0.1)
				(type default)
			)
			(layer "B.Fab")
		)
		(fp_line
			(start 0.12065 -0.2794)
			(end -0.12065 -0.2794)
			(stroke
				(width 0.1)
				(type default)
			)
			(layer "B.Fab")
		)
		(fp_line
			(start 0.12065 -0.305054)
			(end 0.12065 -0.2794)
			(stroke
				(width 0.1)
				(type default)
			)
			(layer "B.Fab")
		)
		(fp_line
			(start -0.120396 0.3048)
			(end -0.120396 0.2794)
			(stroke
				(width 0.1)
				(type default)
			)
			(layer "B.Fab")
		)
		(fp_line
			(start -0.120396 0.2794)
			(end 0.12065 0.2794)
			(stroke
				(width 0.1)
				(type default)
			)
			(layer "B.Fab")
		)
		(fp_line
			(start -0.12065 -0.2794)
			(end -0.12065 -0.3048)
			(stroke
				(width 0.1)
				(type default)
			)
			(layer "B.Fab")
		)
		(fp_line
			(start -0.12065 -0.3048)
			(end -0.67945 -0.3048)
			(stroke
				(width 0.1)
				(type default)
			)
			(layer "B.Fab")
		)
		(fp_line
			(start -0.67945 0.3048)
			(end -0.120396 0.3048)
			(stroke
				(width 0.1)
				(type default)
			)
			(layer "B.Fab")
		)
		(fp_line
			(start -0.67945 -0.3048)
			(end -0.67945 0.3048)
			(stroke
				(width 0.1)
				(type default)
			)
			(layer "B.Fab")
		)
		(pad "1" smd circle
			(at 0.40005 0)
			(size 0 0)
			(layers "B.Cu" "B.Mask" "B.Paste")
			(net "AC_PWR_BMC_BTN_R_N")
		)
		(pad "2" smd circle
			(at -0.40005 0)
			(size 0 0)
			(layers "B.Cu" "B.Mask" "B.Paste")
			(net "AC_PWR_BMC_BTN_N")
		)
	)
	(footprint ""
		(layer "B.Cu")
		(at 47.92726 -67.818 180)
		(property "Reference" "R842"
			(at 0 0 0)
			(layer "B.SilkS")
			(hide yes)
			(effects
				(font
					(size 1.27 1.27)
				)
				(justify mirror)
			)
		)
		(property "Value" ""
			(at 0 0 0)
			(layer "B.Fab")
			(effects
				(font
					(size 1.27 1.27)
				)
				(justify mirror)
			)
		)
		(duplicate_pad_numbers_are_jumpers no)
		(fp_line
			(start 0.7874 0.4064)
			(end 0.7874 -0.4064)
			(stroke
				(width 0.1524)
				(type default)
			)
			(layer "B.SilkS")
		)
		(fp_line
			(start 0.7874 -0.4064)
			(end -0.7874 -0.4064)
			(stroke
				(width 0.1524)
				(type default)
			)
			(layer "B.SilkS")
		)
		(fp_line
			(start -0.7874 0.4064)
			(end 0.7874 0.4064)
			(stroke
				(width 0.1524)
				(type default)
			)
			(layer "B.SilkS")
		)
		(fp_line
			(start -0.7874 -0.4064)
			(end -0.7874 0.4064)
			(stroke
				(width 0.1524)
				(type default)
			)
			(layer "B.SilkS")
		)
		(fp_line
			(start 0.67945 0.3048)
			(end 0.67945 -0.305054)
			(stroke
				(width 0.1)
				(type default)
			)
			(layer "B.Fab")
		)
		(fp_line
			(start 0.67945 -0.305054)
			(end 0.12065 -0.305054)
			(stroke
				(width 0.1)
				(type default)
			)
			(layer "B.Fab")
		)
		(fp_line
			(start 0.12065 0.3048)
			(end 0.67945 0.3048)
			(stroke
				(width 0.1)
				(type default)
			)
			(layer "B.Fab")
		)
		(fp_line
			(start 0.12065 0.2794)
			(end 0.12065 0.3048)
			(stroke
				(width 0.1)
				(type default)
			)
			(layer "B.Fab")
		)
		(fp_line
			(start 0.12065 -0.2794)
			(end -0.12065 -0.2794)
			(stroke
				(width 0.1)
				(type default)
			)
			(layer "B.Fab")
		)
		(fp_line
			(start 0.12065 -0.305054)
			(end 0.12065 -0.2794)
			(stroke
				(width 0.1)
				(type default)
			)
			(layer "B.Fab")
		)
		(fp_line
			(start -0.120396 0.3048)
			(end -0.120396 0.2794)
			(stroke
				(width 0.1)
				(type default)
			)
			(layer "B.Fab")
		)
		(fp_line
			(start -0.120396 0.2794)
			(end 0.12065 0.2794)
			(stroke
				(width 0.1)
				(type default)
			)
			(layer "B.Fab")
		)
		(fp_line
			(start -0.12065 -0.2794)
			(end -0.12065 -0.3048)
			(stroke
				(width 0.1)
				(type default)
			)
			(layer "B.Fab")
		)
		(fp_line
			(start -0.12065 -0.3048)
			(end -0.67945 -0.3048)
			(stroke
				(width 0.1)
				(type default)
			)
			(layer "B.Fab")
		)
		(fp_line
			(start -0.67945 0.3048)
			(end -0.120396 0.3048)
			(stroke
				(width 0.1)
				(type default)
			)
			(layer "B.Fab")
		)
		(fp_line
			(start -0.67945 -0.3048)
			(end -0.67945 0.3048)
			(stroke
				(width 0.1)
				(type default)
			)
			(layer "B.Fab")
		)
		(pad "1" smd circle
			(at 0.40005 0)
			(size 0 0)
			(layers "B.Cu" "B.Mask" "B.Paste")
			(net "P3V3_AUX")
		)
		(pad "2" smd circle
			(at -0.40005 0)
			(size 0 0)
			(layers "B.Cu" "B.Mask" "B.Paste")
			(net "SMB_BMC_ALERT9_N")
		)
	)
	(footprint ""
		(layer "B.Cu")
		(at 31.496 -70.358 180)
		(property "Reference" "C11"
			(at 0 0 0)
			(layer "B.SilkS")
			(hide yes)
			(effects
				(font
					(size 1.27 1.27)
				)
				(justify mirror)
			)
		)
		(property "Value" ""
			(at 0 0 0)
			(layer "B.Fab")
			(effects
				(font
					(size 1.27 1.27)
				)
				(justify mirror)
			)
		)
		(duplicate_pad_numbers_are_jumpers no)
		(fp_line
			(start 0.7874 0.4064)
			(end 0.7874 -0.4064)
			(stroke
				(width 0.1524)
				(type default)
			)
			(layer "B.SilkS")
		)
		(fp_line
			(start 0.7874 -0.4064)
			(end -0.7874 -0.4064)
			(stroke
				(width 0.1524)
				(type default)
			)
			(layer "B.SilkS")
		)
		(fp_line
			(start -0.7874 0.4064)
			(end 0.7874 0.4064)
			(stroke
				(width 0.1524)
				(type default)
			)
			(layer "B.SilkS")
		)
		(fp_line
			(start -0.7874 -0.4064)
			(end -0.7874 0.4064)
			(stroke
				(width 0.1524)
				(type default)
			)
			(layer "B.SilkS")
		)
		(fp_line
			(start 0.67945 0.3048)
			(end 0.67945 -0.305054)
			(stroke
				(width 0.1)
				(type default)
			)
			(layer "B.Fab")
		)
		(fp_line
			(start 0.67945 -0.305054)
			(end 0.12065 -0.305054)
			(stroke
				(width 0.1)
				(type default)
			)
			(layer "B.Fab")
		)
		(fp_line
			(start 0.12065 0.3048)
			(end 0.67945 0.3048)
			(stroke
				(width 0.1)
				(type default)
			)
			(layer "B.Fab")
		)
		(fp_line
			(start 0.12065 0.2794)
			(end 0.12065 0.3048)
			(stroke
				(width 0.1)
				(type default)
			)
			(layer "B.Fab")
		)
		(fp_line
			(start 0.12065 -0.2794)
			(end -0.12065 -0.2794)
			(stroke
				(width 0.1)
				(type default)
			)
			(layer "B.Fab")
		)
		(fp_line
			(start 0.12065 -0.305054)
			(end 0.12065 -0.2794)
			(stroke
				(width 0.1)
				(type default)
			)
			(layer "B.Fab")
		)
		(fp_line
			(start -0.120396 0.3048)
			(end -0.120396 0.2794)
			(stroke
				(width 0.1)
				(type default)
			)
			(layer "B.Fab")
		)
		(fp_line
			(start -0.120396 0.2794)
			(end 0.12065 0.2794)
			(stroke
				(width 0.1)
				(type default)
			)
			(layer "B.Fab")
		)
		(fp_line
			(start -0.12065 -0.2794)
			(end -0.12065 -0.3048)
			(stroke
				(width 0.1)
				(type default)
			)
			(layer "B.Fab")
		)
		(fp_line
			(start -0.12065 -0.3048)
			(end -0.67945 -0.3048)
			(stroke
				(width 0.1)
				(type default)
			)
			(layer "B.Fab")
		)
		(fp_line
			(start -0.67945 0.3048)
			(end -0.120396 0.3048)
			(stroke
				(width 0.1)
				(type default)
			)
			(layer "B.Fab")
		)
		(fp_line
			(start -0.67945 -0.3048)
			(end -0.67945 0.3048)
			(stroke
				(width 0.1)
				(type default)
			)
			(layer "B.Fab")
		)
		(pad "1" smd circle
			(at 0.40005 0)
			(size 0 0)
			(layers "B.Cu" "B.Mask" "B.Paste")
			(net "P3V3_AUX")
		)
		(pad "2" smd circle
			(at -0.40005 0)
			(size 0 0)
			(layers "B.Cu" "B.Mask" "B.Paste")
			(net "GND")
		)
	)
	(footprint ""
		(layer "B.Cu")
		(at 63.9572 -90.2208)
		(property "Reference" "R740"
			(at 0 0 0)
			(layer "B.SilkS")
			(hide yes)
			(effects
				(font
					(size 1.27 1.27)
				)
				(justify mirror)
			)
		)
		(property "Value" ""
			(at 0 0 0)
			(layer "B.Fab")
			(effects
				(font
					(size 1.27 1.27)
				)
				(justify mirror)
			)
		)
		(duplicate_pad_numbers_are_jumpers no)
		(fp_line
			(start -0.7874 -0.4064)
			(end -0.7874 0.4064)
			(stroke
				(width 0.1524)
				(type default)
			)
			(layer "B.SilkS")
		)
		(fp_line
			(start -0.7874 0.4064)
			(end 0.7874 0.4064)
			(stroke
				(width 0.1524)
				(type default)
			)
			(layer "B.SilkS")
		)
		(fp_line
			(start 0.7874 -0.4064)
			(end -0.7874 -0.4064)
			(stroke
				(width 0.1524)
				(type default)
			)
			(layer "B.SilkS")
		)
		(fp_line
			(start 0.7874 0.4064)
			(end 0.7874 -0.4064)
			(stroke
				(width 0.1524)
				(type default)
			)
			(layer "B.SilkS")
		)
		(fp_line
			(start -0.67945 -0.3048)
			(end -0.67945 0.3048)
			(stroke
				(width 0.1)
				(type default)
			)
			(layer "B.Fab")
		)
		(fp_line
			(start -0.67945 0.3048)
			(end -0.120396 0.3048)
			(stroke
				(width 0.1)
				(type default)
			)
			(layer "B.Fab")
		)
		(fp_line
			(start -0.12065 -0.3048)
			(end -0.67945 -0.3048)
			(stroke
				(width 0.1)
				(type default)
			)
			(layer "B.Fab")
		)
		(fp_line
			(start -0.12065 -0.2794)
			(end -0.12065 -0.3048)
			(stroke
				(width 0.1)
				(type default)
			)
			(layer "B.Fab")
		)
		(fp_line
			(start -0.120396 0.2794)
			(end 0.12065 0.2794)
			(stroke
				(width 0.1)
				(type default)
			)
			(layer "B.Fab")
		)
		(fp_line
			(start -0.120396 0.3048)
			(end -0.120396 0.2794)
			(stroke
				(width 0.1)
				(type default)
			)
			(layer "B.Fab")
		)
		(fp_line
			(start 0.12065 -0.305054)
			(end 0.12065 -0.2794)
			(stroke
				(width 0.1)
				(type default)
			)
			(layer "B.Fab")
		)
		(fp_line
			(start 0.12065 -0.2794)
			(end -0.12065 -0.2794)
			(stroke
				(width 0.1)
				(type default)
			)
			(layer "B.Fab")
		)
		(fp_line
			(start 0.12065 0.2794)
			(end 0.12065 0.3048)
			(stroke
				(width 0.1)
				(type default)
			)
			(layer "B.Fab")
		)
		(fp_line
			(start 0.12065 0.3048)
			(end 0.67945 0.3048)
			(stroke
				(width 0.1)
				(type default)
			)
			(layer "B.Fab")
		)
		(fp_line
			(start 0.67945 -0.305054)
			(end 0.12065 -0.305054)
			(stroke
				(width 0.1)
				(type default)
			)
			(layer "B.Fab")
		)
		(fp_line
			(start 0.67945 0.3048)
			(end 0.67945 -0.305054)
			(stroke
				(width 0.1)
				(type default)
			)
			(layer "B.Fab")
		)
		(pad "1" smd circle
			(at 0.40005 0 180)
			(size 0 0)
			(layers "B.Cu" "B.Mask" "B.Paste")
			(net "P3V3_AUX")
		)
		(pad "2" smd circle
			(at -0.40005 0 180)
			(size 0 0)
			(layers "B.Cu" "B.Mask" "B.Paste")
			(net "LED_POSTCODE_A2")
		)
	)
)
